(kicad_pcb
	(version 20260206)
	(generator "pcbnew")
	(generator_version "10.0")
	(general
		(thickness 1.6)
		(legacy_teardrops no)
	)
	(paper "A4")
	(title_block
		(title "04192023_DAF0TMB3IC0_F0TG_MB_C_brd_V02_OCP.brd")
		(comment 1 "Grand Teton / footprints 7398-7404 of 8354")
	)
	(layers
		(0 "F.Cu" signal "TOP")
		(4 "In1.Cu" signal "GND")
		(6 "In2.Cu" signal "IN1")
		(8 "In3.Cu" signal "GND1")
		(10 "In4.Cu" signal "IN2")
		(12 "In5.Cu" signal "GND2")
		(14 "In6.Cu" signal "IN3")
		(16 "In7.Cu" signal "GND3")
		(18 "In8.Cu" signal "VCC")
		(20 "In9.Cu" signal "VCC1")
		(22 "In10.Cu" signal "GND4")
		(24 "In11.Cu" signal "IN4")
		(26 "In12.Cu" signal "GND5")
		(28 "In13.Cu" signal "IN5")
		(30 "In14.Cu" signal "GND6")
		(32 "In15.Cu" signal "IN6")
		(34 "In16.Cu" signal "GND7")
		(2 "B.Cu" signal "BOTTOM")
		(9 "F.Adhes" user "F.Adhesive")
		(11 "B.Adhes" user "B.Adhesive")
		(13 "F.Paste" user "Package Geometry/Pastemask Top")
		(15 "B.Paste" user "Package Geometry/Pastemask Bottom")
		(5 "F.SilkS" user "Ref Des/Silkscreen Top")
		(7 "B.SilkS" user "Ref Des/Silkscreen Bottom")
		(1 "F.Mask" user "Board Geometry/Soldermask Top")
		(3 "B.Mask" user "Board Geometry/Soldermask Bottom")
		(17 "Dwgs.User" user "User.Drawings")
		(19 "Cmts.User" user "User.Comments")
		(21 "Eco1.User" user "User.Eco1")
		(23 "Eco2.User" user "User.Eco2")
		(25 "Edge.Cuts" user "Board Geometry/Outline")
		(27 "Margin" user)
		(31 "F.CrtYd" user "Package Geometry/Place Bound Top")
		(29 "B.CrtYd" user "Package Geometry/Place Bound Bottom")
		(35 "F.Fab" user "Ref Des/Assembly Top")
		(33 "B.Fab" user "Ref Des/Assembly Bottom")
	)
	(footprint ""
		(layer "B.Cu")
		(at 244.221 -228.092 -90)
		(property "Reference" "R1154"
			(at 0 0 90)
			(layer "B.SilkS")
			(hide yes)
			(effects
				(font
					(size 1.27 1.27)
				)
				(justify mirror)
			)
		)
		(property "Value" ""
			(at 0 0 90)
			(layer "B.Fab")
			(effects
				(font
					(size 1.27 1.27)
				)
				(justify mirror)
			)
		)
		(duplicate_pad_numbers_are_jumpers no)
		(fp_line
			(start -0.7874 0.4064)
			(end 0.7874 0.4064)
			(stroke
				(width 0.1524)
				(type default)
			)
			(layer "B.SilkS")
		)
		(fp_line
			(start 0.7874 0.4064)
			(end 0.7874 -0.4064)
			(stroke
				(width 0.1524)
				(type default)
			)
			(layer "B.SilkS")
		)
		(fp_line
			(start -0.7874 -0.4064)
			(end -0.7874 0.4064)
			(stroke
				(width 0.1524)
				(type default)
			)
			(layer "B.SilkS")
		)
		(fp_line
			(start 0.7874 -0.4064)
			(end -0.7874 -0.4064)
			(stroke
				(width 0.1524)
				(type default)
			)
			(layer "B.SilkS")
		)
		(fp_line
			(start -0.67945 0.3048)
			(end -0.120396 0.3048)
			(stroke
				(width 0.1)
				(type default)
			)
			(layer "B.Fab")
		)
		(fp_line
			(start -0.120396 0.3048)
			(end -0.120396 0.2794)
			(stroke
				(width 0.1)
				(type default)
			)
			(layer "B.Fab")
		)
		(fp_line
			(start 0.12065 0.3048)
			(end 0.67945 0.3048)
			(stroke
				(width 0.1)
				(type default)
			)
			(layer "B.Fab")
		)
		(fp_line
			(start 0.67945 0.3048)
			(end 0.67945 -0.305054)
			(stroke
				(width 0.1)
				(type default)
			)
			(layer "B.Fab")
		)
		(fp_line
			(start -0.120396 0.2794)
			(end 0.12065 0.2794)
			(stroke
				(width 0.1)
				(type default)
			)
			(layer "B.Fab")
		)
		(fp_line
			(start 0.12065 0.2794)
			(end 0.12065 0.3048)
			(stroke
				(width 0.1)
				(type default)
			)
			(layer "B.Fab")
		)
		(fp_line
			(start -0.12065 -0.2794)
			(end -0.12065 -0.3048)
			(stroke
				(width 0.1)
				(type default)
			)
			(layer "B.Fab")
		)
		(fp_line
			(start 0.12065 -0.2794)
			(end -0.12065 -0.2794)
			(stroke
				(width 0.1)
				(type default)
			)
			(layer "B.Fab")
		)
		(fp_line
			(start -0.67945 -0.3048)
			(end -0.67945 0.3048)
			(stroke
				(width 0.1)
				(type default)
			)
			(layer "B.Fab")
		)
		(fp_line
			(start -0.12065 -0.3048)
			(end -0.67945 -0.3048)
			(stroke
				(width 0.1)
				(type default)
			)
			(layer "B.Fab")
		)
		(fp_line
			(start 0.12065 -0.305054)
			(end 0.12065 -0.2794)
			(stroke
				(width 0.1)
				(type default)
			)
			(layer "B.Fab")
		)
		(fp_line
			(start 0.67945 -0.305054)
			(end 0.12065 -0.305054)
			(stroke
				(width 0.1)
				(type default)
			)
			(layer "B.Fab")
		)
		(pad "1" smd circle
			(at 0.40005 0 90)
			(size 0 0)
			(layers "B.Cu" "B.Mask" "B.Paste")
			(net "SMB_CPU0_CPU1_SEC_SDA_R1")
		)
		(pad "2" smd circle
			(at -0.40005 0 90)
			(size 0 0)
			(layers "B.Cu" "B.Mask" "B.Paste")
			(net "SMB_CPU0_CPU1_SEC_SDA_R2")
		)
	)
	(footprint ""
		(layer "B.Cu")
		(at 323.386958 -198.964296)
		(property "Reference" "R438"
			(at 0 0 0)
			(layer "B.SilkS")
			(hide yes)
			(effects
				(font
					(size 1.27 1.27)
				)
				(justify mirror)
			)
		)
		(property "Value" ""
			(at 0 0 0)
			(layer "B.Fab")
			(effects
				(font
					(size 1.27 1.27)
				)
				(justify mirror)
			)
		)
		(duplicate_pad_numbers_are_jumpers no)
		(fp_line
			(start -0.7874 -0.4064)
			(end -0.7874 0.4064)
			(stroke
				(width 0.1524)
				(type default)
			)
			(layer "B.SilkS")
		)
		(fp_line
			(start -0.7874 0.4064)
			(end 0.7874 0.4064)
			(stroke
				(width 0.1524)
				(type default)
			)
			(layer "B.SilkS")
		)
		(fp_line
			(start 0.7874 -0.4064)
			(end -0.7874 -0.4064)
			(stroke
				(width 0.1524)
				(type default)
			)
			(layer "B.SilkS")
		)
		(fp_line
			(start 0.7874 0.4064)
			(end 0.7874 -0.4064)
			(stroke
				(width 0.1524)
				(type default)
			)
			(layer "B.SilkS")
		)
		(fp_line
			(start -0.67945 -0.3048)
			(end -0.67945 0.3048)
			(stroke
				(width 0.1)
				(type default)
			)
			(layer "B.Fab")
		)
		(fp_line
			(start -0.67945 0.3048)
			(end -0.120396 0.3048)
			(stroke
				(width 0.1)
				(type default)
			)
			(layer "B.Fab")
		)
		(fp_line
			(start -0.12065 -0.3048)
			(end -0.67945 -0.3048)
			(stroke
				(width 0.1)
				(type default)
			)
			(layer "B.Fab")
		)
		(fp_line
			(start -0.12065 -0.2794)
			(end -0.12065 -0.3048)
			(stroke
				(width 0.1)
				(type default)
			)
			(layer "B.Fab")
		)
		(fp_line
			(start -0.120396 0.2794)
			(end 0.12065 0.2794)
			(stroke
				(width 0.1)
				(type default)
			)
			(layer "B.Fab")
		)
		(fp_line
			(start -0.120396 0.3048)
			(end -0.120396 0.2794)
			(stroke
				(width 0.1)
				(type default)
			)
			(layer "B.Fab")
		)
		(fp_line
			(start 0.12065 -0.305054)
			(end 0.12065 -0.2794)
			(stroke
				(width 0.1)
				(type default)
			)
			(layer "B.Fab")
		)
		(fp_line
			(start 0.12065 -0.2794)
			(end -0.12065 -0.2794)
			(stroke
				(width 0.1)
				(type default)
			)
			(layer "B.Fab")
		)
		(fp_line
			(start 0.12065 0.2794)
			(end 0.12065 0.3048)
			(stroke
				(width 0.1)
				(type default)
			)
			(layer "B.Fab")
		)
		(fp_line
			(start 0.12065 0.3048)
			(end 0.67945 0.3048)
			(stroke
				(width 0.1)
				(type default)
			)
			(layer "B.Fab")
		)
		(fp_line
			(start 0.67945 -0.305054)
			(end 0.12065 -0.305054)
			(stroke
				(width 0.1)
				(type default)
			)
			(layer "B.Fab")
		)
		(fp_line
			(start 0.67945 0.3048)
			(end 0.67945 -0.305054)
			(stroke
				(width 0.1)
				(type default)
			)
			(layer "B.Fab")
		)
		(pad "1" smd circle
			(at 0.40005 0 180)
			(size 0 0)
			(layers "B.Cu" "B.Mask" "B.Paste")
			(net "CPU0_FORCE_SELFREFRESH")
		)
		(pad "2" smd circle
			(at -0.40005 0 180)
			(size 0 0)
			(layers "B.Cu" "B.Mask" "B.Paste")
			(net "PVDD18_S5_P0")
		)
	)
	(footprint ""
		(layer "B.Cu")
		(at 436.839614 -351.095818 90)
		(property "Reference" "PC218_2"
			(at 0 0 90)
			(layer "B.SilkS")
			(hide yes)
			(effects
				(font
					(size 1.27 1.27)
				)
				(justify mirror)
			)
		)
		(property "Value" ""
			(at 0 0 90)
			(layer "B.Fab")
			(effects
				(font
					(size 1.27 1.27)
				)
				(justify mirror)
			)
		)
		(duplicate_pad_numbers_are_jumpers no)
		(fp_line
			(start 1.524 -0.762)
			(end -1.524 -0.762)
			(stroke
				(width 0.1524)
				(type default)
			)
			(layer "B.SilkS")
		)
		(fp_line
			(start -1.524 -0.762)
			(end -1.524 0.762)
			(stroke
				(width 0.1524)
				(type default)
			)
			(layer "B.SilkS")
		)
		(fp_line
			(start 1.524 0.762)
			(end 1.524 -0.762)
			(stroke
				(width 0.1524)
				(type default)
			)
			(layer "B.SilkS")
		)
		(fp_line
			(start -1.524 0.762)
			(end 1.524 0.762)
			(stroke
				(width 0.1524)
				(type default)
			)
			(layer "B.SilkS")
		)
		(fp_line
			(start 1.1049 -0.724916)
			(end 1.1049 0.724916)
			(stroke
				(width 0.1)
				(type default)
			)
			(layer "B.Fab")
		)
		(fp_line
			(start -1.1049 -0.724916)
			(end 1.1049 -0.724916)
			(stroke
				(width 0.1)
				(type default)
			)
			(layer "B.Fab")
		)
		(fp_line
			(start 1.1049 0.724916)
			(end -1.1049 0.724916)
			(stroke
				(width 0.1)
				(type default)
			)
			(layer "B.Fab")
		)
		(fp_line
			(start -1.1049 0.724916)
			(end -1.1049 -0.724916)
			(stroke
				(width 0.1)
				(type default)
			)
			(layer "B.Fab")
		)
		(pad "1" smd rect
			(at 0.889 0 90)
			(size 1.016 1.27)
			(layers "B.Cu" "B.Mask" "B.Paste")
			(net "SW_P12V_AUX_PVDD11_S3_P0_FLT")
		)
		(pad "2" smd rect
			(at -0.889 0 90)
			(size 1.016 1.27)
			(layers "B.Cu" "B.Mask" "B.Paste")
			(net "GND")
		)
	)
	(footprint ""
		(layer "B.Cu")
		(at 269.648178 -192.660016)
		(property "Reference" "C154"
			(at 0 0 0)
			(layer "B.SilkS")
			(hide yes)
			(effects
				(font
					(size 1.27 1.27)
				)
				(justify mirror)
			)
		)
		(property "Value" ""
			(at 0 0 0)
			(layer "B.Fab")
			(effects
				(font
					(size 1.27 1.27)
				)
				(justify mirror)
			)
		)
		(duplicate_pad_numbers_are_jumpers no)
		(fp_line
			(start -1.524 -0.762)
			(end -1.524 0.762)
			(stroke
				(width 0.1524)
				(type default)
			)
			(layer "B.SilkS")
		)
		(fp_line
			(start -1.524 0.762)
			(end 1.524 0.762)
			(stroke
				(width 0.1524)
				(type default)
			)
			(layer "B.SilkS")
		)
		(fp_line
			(start 1.524 -0.762)
			(end -1.524 -0.762)
			(stroke
				(width 0.1524)
				(type default)
			)
			(layer "B.SilkS")
		)
		(fp_line
			(start 1.524 0.762)
			(end 1.524 -0.762)
			(stroke
				(width 0.1524)
				(type default)
			)
			(layer "B.SilkS")
		)
		(fp_line
			(start -1.1049 -0.724916)
			(end 1.1049 -0.724916)
			(stroke
				(width 0.1)
				(type default)
			)
			(layer "B.Fab")
		)
		(fp_line
			(start -1.1049 0.724916)
			(end -1.1049 -0.724916)
			(stroke
				(width 0.1)
				(type default)
			)
			(layer "B.Fab")
		)
		(fp_line
			(start 1.1049 -0.724916)
			(end 1.1049 0.724916)
			(stroke
				(width 0.1)
				(type default)
			)
			(layer "B.Fab")
		)
		(fp_line
			(start 1.1049 0.724916)
			(end -1.1049 0.724916)
			(stroke
				(width 0.1)
				(type default)
			)
			(layer "B.Fab")
		)
		(pad "1" smd rect
			(at 0.889 0)
			(size 1.016 1.27)
			(layers "B.Cu" "B.Mask" "B.Paste")
			(net "P12V_MEM_CPU0")
		)
		(pad "2" smd rect
			(at -0.889 0)
			(size 1.016 1.27)
			(layers "B.Cu" "B.Mask" "B.Paste")
			(net "GND")
		)
	)
	(footprint ""
		(layer "B.Cu")
		(at 407.819098 -398.942052 90)
		(property "Reference" "C799"
			(at 0 0 90)
			(layer "B.SilkS")
			(hide yes)
			(effects
				(font
					(size 1.27 1.27)
				)
				(justify mirror)
			)
		)
		(property "Value" ""
			(at 0 0 90)
			(layer "B.Fab")
			(effects
				(font
					(size 1.27 1.27)
				)
				(justify mirror)
			)
		)
		(duplicate_pad_numbers_are_jumpers no)
		(fp_line
			(start 0.7874 -0.4064)
			(end -0.7874 -0.4064)
			(stroke
				(width 0.1524)
				(type default)
			)
			(layer "B.SilkS")
		)
		(fp_line
			(start -0.7874 -0.4064)
			(end -0.7874 0.4064)
			(stroke
				(width 0.1524)
				(type default)
			)
			(layer "B.SilkS")
		)
		(fp_line
			(start 0.7874 0.4064)
			(end 0.7874 -0.4064)
			(stroke
				(width 0.1524)
				(type default)
			)
			(layer "B.SilkS")
		)
		(fp_line
			(start -0.7874 0.4064)
			(end 0.7874 0.4064)
			(stroke
				(width 0.1524)
				(type default)
			)
			(layer "B.SilkS")
		)
		(fp_line
			(start 0.67945 -0.305054)
			(end 0.12065 -0.305054)
			(stroke
				(width 0.1)
				(type default)
			)
			(layer "B.Fab")
		)
		(fp_line
			(start 0.12065 -0.305054)
			(end 0.12065 -0.2794)
			(stroke
				(width 0.1)
				(type default)
			)
			(layer "B.Fab")
		)
		(fp_line
			(start -0.12065 -0.3048)
			(end -0.67945 -0.3048)
			(stroke
				(width 0.1)
				(type default)
			)
			(layer "B.Fab")
		)
		(fp_line
			(start -0.67945 -0.3048)
			(end -0.67945 0.3048)
			(stroke
				(width 0.1)
				(type default)
			)
			(layer "B.Fab")
		)
		(fp_line
			(start 0.12065 -0.2794)
			(end -0.12065 -0.2794)
			(stroke
				(width 0.1)
				(type default)
			)
			(layer "B.Fab")
		)
		(fp_line
			(start -0.12065 -0.2794)
			(end -0.12065 -0.3048)
			(stroke
				(width 0.1)
				(type default)
			)
			(layer "B.Fab")
		)
		(fp_line
			(start 0.12065 0.2794)
			(end 0.12065 0.3048)
			(stroke
				(width 0.1)
				(type default)
			)
			(layer "B.Fab")
		)
		(fp_line
			(start -0.120396 0.2794)
			(end 0.12065 0.2794)
			(stroke
				(width 0.1)
				(type default)
			)
			(layer "B.Fab")
		)
		(fp_line
			(start 0.67945 0.3048)
			(end 0.67945 -0.305054)
			(stroke
				(width 0.1)
				(type default)
			)
			(layer "B.Fab")
		)
		(fp_line
			(start 0.12065 0.3048)
			(end 0.67945 0.3048)
			(stroke
				(width 0.1)
				(type default)
			)
			(layer "B.Fab")
		)
		(fp_line
			(start -0.120396 0.3048)
			(end -0.120396 0.2794)
			(stroke
				(width 0.1)
				(type default)
			)
			(layer "B.Fab")
		)
		(fp_line
			(start -0.67945 0.3048)
			(end -0.120396 0.3048)
			(stroke
				(width 0.1)
				(type default)
			)
			(layer "B.Fab")
		)
		(pad "1" smd circle
			(at 0.40005 0 270)
			(size 0 0)
			(layers "B.Cu" "B.Mask" "B.Paste")
			(net "P0V9_CPU0_RT2_2A")
		)
		(pad "2" smd circle
			(at -0.40005 0 270)
			(size 0 0)
			(layers "B.Cu" "B.Mask" "B.Paste")
			(net "GND")
		)
	)
	(footprint ""
		(layer "B.Cu")
		(at 482.66985 7.613142 90)
		(property "Reference" "X8006"
			(at 0.93726 -1.53035 270)
			(unlocked yes)
			(layer "B.SilkS")
			(effects
				(font
					(size 0.7874 0.5842)
					(thickness 0.1524)
				)
				(justify left mirror)
			)
		)
		(property "Value" ""
			(at 0 0 90)
			(layer "B.Fab")
			(effects
				(font
					(size 1.27 1.27)
				)
				(justify mirror)
			)
		)
		(property "Device Type" "TP_TDR_4P_FTS_TH-TP_TDR_4P_DIP,EMPTY,TP15"
			(at -1.30175 1.27 0)
			(unlocked yes)
			(layer "B.Fab")
			(hide yes)
			(effects
				(font
					(size 0.635 0.4064)
					(thickness 0.1524)
				)
				(justify mirror)
			)
		)
		(property "User Part Number" "N_A"
			(at -1.30175 1.27 0)
			(unlocked yes)
			(layer "Cmts.User")
			(hide yes)
			(effects
				(font
					(size 0.635 0.4064)
					(thickness 0.1524)
				)
				(justify mirror)
			)
		)
		(duplicate_pad_numbers_are_jumpers no)
		(fp_line
			(start 0 -1.27)
			(end 0 -0.635)
			(stroke
				(width 0.1524)
				(type default)
			)
			(layer "B.SilkS")
		)
		(fp_line
			(start -2.54 -1.27)
			(end 0 -1.27)
			(stroke
				(width 0.1524)
				(type default)
			)
			(layer "B.SilkS")
		)
		(fp_line
			(start -2.54 -1.1303)
			(end -2.54 -1.27)
			(stroke
				(width 0.1524)
				(type default)
			)
			(layer "B.SilkS")
		)
		(fp_line
			(start 0 0.635)
			(end 0 1.905)
			(stroke
				(width 0.1524)
				(type default)
			)
			(layer "B.SilkS")
		)
		(fp_line
			(start -2.54 1.4097)
			(end -2.54 1.1303)
			(stroke
				(width 0.1524)
				(type default)
			)
			(layer "B.SilkS")
		)
		(fp_line
			(start 0 3.175)
			(end 0 3.81)
			(stroke
				(width 0.1524)
				(type default)
			)
			(layer "B.SilkS")
		)
		(fp_line
			(start 0 3.81)
			(end -2.54 3.81)
			(stroke
				(width 0.1524)
				(type default)
			)
			(layer "B.SilkS")
		)
		(fp_line
			(start -2.54 3.81)
			(end -2.54 3.6703)
			(stroke
				(width 0.1524)
				(type default)
			)
			(layer "B.SilkS")
		)
		(fp_poly
			(pts
				(xy 0.761746 0) (xy 2.285746 -0.762) (xy 2.285746 0.762)
			)
			(stroke
				(width 0)
				(type default)
			)
			(fill yes)
			(layer "B.SilkS")
		)
		(fp_line
			(start 0 -1.27)
			(end 0 3.81)
			(stroke
				(width 0.1)
				(type default)
			)
			(layer "B.Fab")
		)
		(fp_line
			(start -2.54 -1.27)
			(end 0 -1.27)
			(stroke
				(width 0.1)
				(type default)
			)
			(layer "B.Fab")
		)
		(fp_line
			(start 0 3.81)
			(end -2.54 3.81)
			(stroke
				(width 0.1)
				(type default)
			)
			(layer "B.Fab")
		)
		(fp_line
			(start -2.54 3.81)
			(end -2.54 -1.27)
			(stroke
				(width 0.1)
				(type default)
			)
			(layer "B.Fab")
		)
		(fp_poly
			(pts
				(xy 0.761746 0) (xy 2.285746 -0.762) (xy 2.285746 0.762)
			)
			(stroke
				(width 0)
				(type default)
			)
			(fill yes)
			(layer "B.Fab")
		)
		(pad "1" thru_hole circle
			(at 0 0 270)
			(size 1.0033 1.0033)
			(drill 0.249936)
			(layers "*.Cu" "*.Mask")
			(remove_unused_layers no)
			(net "TDR_DIFF_85_BOT_DP")
			(clearance 0.10795)
			(padstack
				(mode front_inner_back)
				(layer "Inner"
					(shape circle)
					(size 0.8001 0.8001)
					(clearance 0.1524)
				)
				(layer "B.Cu"
					(shape circle)
					(size 1.0033 1.0033)
					(thermal_gap 0.10795)
					(clearance 0.10795)
				)
			)
		)
		(pad "2" thru_hole circle
			(at -2.54 0 270)
			(size 1.9939 1.9939)
			(drill 0.249936)
			(layers "*.Cu" "*.Mask")
			(remove_unused_layers no)
			(net "T1_GND")
			(clearance 0.10795)
			(padstack
				(mode front_inner_back)
				(layer "Inner"
					(shape circle)
					(size 0.8001 0.8001)
					(clearance 0.1524)
				)
				(layer "B.Cu"
					(shape circle)
					(size 1.9939 1.9939)
					(thermal_gap 0.10795)
					(clearance 0.10795)
				)
			)
		)
		(pad "3" thru_hole circle
			(at -2.54 2.54 270)
			(size 1.9939 1.9939)
			(drill 0.249936)
			(layers "*.Cu" "*.Mask")
			(remove_unused_layers no)
			(net "T1_GND")
			(clearance 0.10795)
			(padstack
				(mode front_inner_back)
				(layer "Inner"
					(shape circle)
					(size 0.8001 0.8001)
					(clearance 0.1524)
				)
				(layer "B.Cu"
					(shape circle)
					(size 1.9939 1.9939)
					(thermal_gap 0.10795)
					(clearance 0.10795)
				)
			)
		)
		(pad "4" thru_hole circle
			(at 0 2.54 270)
			(size 1.0033 1.0033)
			(drill 0.249936)
			(layers "*.Cu" "*.Mask")
			(remove_unused_layers no)
			(net "TDR_DIFF_85_BOT_DN")
			(clearance 0.10795)
			(padstack
				(mode front_inner_back)
				(layer "Inner"
					(shape circle)
					(size 0.8001 0.8001)
					(clearance 0.1524)
				)
				(layer "B.Cu"
					(shape circle)
					(size 1.0033 1.0033)
					(thermal_gap 0.10795)
					(clearance 0.10795)
				)
			)
		)
	)
	(footprint ""
		(layer "B.Cu")
		(at 130.104642 -76.48321)
		(property "Reference" "PC6024"
			(at 0 0 0)
			(layer "B.SilkS")
			(hide yes)
			(effects
				(font
					(size 1.27 1.27)
				)
				(justify mirror)
			)
		)
		(property "Value" ""
			(at 0 0 0)
			(layer "B.Fab")
			(effects
				(font
					(size 1.27 1.27)
				)
				(justify mirror)
			)
		)
		(duplicate_pad_numbers_are_jumpers no)
		(fp_line
			(start -1.524 -0.762)
			(end -1.524 0.762)
			(stroke
				(width 0.1524)
				(type default)
			)
			(layer "B.SilkS")
		)
		(fp_line
			(start -1.524 0.762)
			(end 1.524 0.762)
			(stroke
				(width 0.1524)
				(type default)
			)
			(layer "B.SilkS")
		)
		(fp_line
			(start 1.524 -0.762)
			(end -1.524 -0.762)
			(stroke
				(width 0.1524)
				(type default)
			)
			(layer "B.SilkS")
		)
		(fp_line
			(start 1.524 0.762)
			(end 1.524 -0.762)
			(stroke
				(width 0.1524)
				(type default)
			)
			(layer "B.SilkS")
		)
		(fp_line
			(start -1.1049 -0.724916)
			(end 1.1049 -0.724916)
			(stroke
				(width 0.1)
				(type default)
			)
			(layer "B.Fab")
		)
		(fp_line
			(start -1.1049 0.724916)
			(end -1.1049 -0.724916)
			(stroke
				(width 0.1)
				(type default)
			)
			(layer "B.Fab")
		)
		(fp_line
			(start 1.1049 -0.724916)
			(end 1.1049 0.724916)
			(stroke
				(width 0.1)
				(type default)
			)
			(layer "B.Fab")
		)
		(fp_line
			(start 1.1049 0.724916)
			(end -1.1049 0.724916)
			(stroke
				(width 0.1)
				(type default)
			)
			(layer "B.Fab")
		)
		(pad "1" smd rect
			(at 0.889 0)
			(size 1.016 1.27)
			(layers "B.Cu" "B.Mask" "B.Paste")
			(net "P1V2_AUX")
		)
		(pad "2" smd rect
			(at -0.889 0)
			(size 1.016 1.27)
			(layers "B.Cu" "B.Mask" "B.Paste")
			(net "GND")
		)
	)
)
